(kicad_pcb
	(version 20260206)
	(generator "pcbnew")
	(generator_version "10.0")
	(general
		(thickness 1.6)
		(legacy_teardrops no)
	)
	(paper "A4")
	(title_block
		(title "peb — Lightning_PEB_BRD.brd")
		(comment 1 "Lightning (Wiwynn / Facebook NVMe JBOF) / footprints 126-133 of 2563")
	)
	(layers
		(0 "F.Cu" signal "TOP")
		(4 "In1.Cu" signal "L2GND")
		(6 "In2.Cu" signal "L3")
		(8 "In3.Cu" signal "L4VCC")
		(10 "In4.Cu" signal "L5VCC")
		(12 "In5.Cu" signal "L6")
		(14 "In6.Cu" signal "L7GND")
		(2 "B.Cu" signal "BOTTOM")
		(9 "F.Adhes" user "F.Adhesive")
		(11 "B.Adhes" user "B.Adhesive")
		(13 "F.Paste" user "Package Geometry/Pastemask Top")
		(15 "B.Paste" user "Package Geometry/Pastemask Bottom")
		(5 "F.SilkS" user "Ref Des/Silkscreen Top")
		(7 "B.SilkS" user "Ref Des/Silkscreen Bottom")
		(1 "F.Mask" user "Board Geometry/Soldermask Top")
		(3 "B.Mask" user "Board Geometry/Soldermask Bottom")
		(17 "Dwgs.User" user "User.Drawings")
		(19 "Cmts.User" user "User.Comments")
		(21 "Eco1.User" user "User.Eco1")
		(23 "Eco2.User" user "User.Eco2")
		(25 "Edge.Cuts" user "Board Geometry/Outline")
		(27 "Margin" user)
		(31 "F.CrtYd" user "Package Geometry/Place Bound Top")
		(29 "B.CrtYd" user "Package Geometry/Place Bound Bottom")
		(35 "F.Fab" user "Ref Des/Assembly Top")
		(33 "B.Fab" user "Ref Des/Assembly Bottom")
	)
	(footprint ""
		(layer "F.Cu")
		(at 18.415 -128.651 -90)
		(property "Reference" "R230"
			(at 0 0 270)
			(layer "F.SilkS")
			(hide yes)
			(effects
				(font
					(size 1.27 1.27)
				)
			)
		)
		(property "Value" "4K7R2F-GP"
			(at 0.064008 -3.993896 270)
			(unlocked yes)
			(layer "F.Fab")
			(hide yes)
			(effects
				(font
					(size 1.016 1.016)
					(thickness 0.1524)
				)
			)
		)
		(property "Device Type" "R402H16"
			(at 0.064008 -5.517896 270)
			(unlocked yes)
			(layer "F.Fab")
			(hide yes)
			(effects
				(font
					(size 1.016 1.016)
					(thickness 0.1524)
				)
			)
		)
		(duplicate_pad_numbers_are_jumpers no)
		(fp_line
			(start -0.508 -0.9398)
			(end -0.508 0.9398)
			(stroke
				(width 0.1524)
				(type default)
			)
			(layer "F.SilkS")
		)
		(fp_line
			(start 0.508 -0.9398)
			(end -0.508 -0.9398)
			(stroke
				(width 0.1524)
				(type default)
			)
			(layer "F.SilkS")
		)
		(fp_rect
			(start -0.508 0.9398)
			(end 0.508 -0.9398)
			(stroke
				(width 0)
				(type default)
			)
			(fill no)
			(layer "F.CrtYd")
		)
		(fp_rect
			(start -0.508 0.9398)
			(end 0.508 -0.9398)
			(stroke
				(width 0)
				(type default)
			)
			(fill no)
			(layer "F.Fab")
		)
		(pad "1" smd custom
			(at 0 -0.4445 270)
			(size 0.1397 0.1397)
			(layers "F.Cu" "F.Mask" "F.Paste")
			(net "GND")
			(options
				(clearance outline)
				(anchor circle)
			)
			(primitives
				(gr_poly
					(pts
						(arc
							(start -0.1778 -0.2794)
							(mid -0.249642 -0.249642)
							(end -0.2794 -0.1778)
						)
						(arc
							(start -0.2794 0.1778)
							(mid -0.249642 0.249642)
							(end -0.1778 0.2794)
						)
						(arc
							(start 0.1778 0.2794)
							(mid 0.249642 0.249642)
							(end 0.2794 0.1778)
						)
						(arc
							(start 0.2794 -0.1778)
							(mid 0.249642 -0.249642)
							(end 0.1778 -0.2794)
						)
					)
					(width 0)
					(fill yes)
				)
			)
		)
		(pad "2" smd custom
			(at 0 0.4445 270)
			(size 0.1397 0.1397)
			(layers "F.Cu" "F.Mask" "F.Paste")
			(net "BMC_PERST#_R")
			(options
				(clearance outline)
				(anchor circle)
			)
			(primitives
				(gr_poly
					(pts
						(arc
							(start -0.1778 -0.2794)
							(mid -0.249642 -0.249642)
							(end -0.2794 -0.1778)
						)
						(arc
							(start -0.2794 0.1778)
							(mid -0.249642 0.249642)
							(end -0.1778 0.2794)
						)
						(arc
							(start 0.1778 0.2794)
							(mid 0.249642 0.249642)
							(end 0.2794 0.1778)
						)
						(arc
							(start 0.2794 -0.1778)
							(mid 0.249642 -0.249642)
							(end 0.1778 -0.2794)
						)
					)
					(width 0)
					(fill yes)
				)
			)
		)
	)
	(footprint ""
		(layer "F.Cu")
		(at 324.45071 -33.482788)
		(property "Reference" "C49"
			(at 0 0 0)
			(layer "F.SilkS")
			(hide yes)
			(effects
				(font
					(size 1.27 1.27)
				)
			)
		)
		(property "Value" "SCD22U10V2KX-1GP"
			(at 1.1811 -2.7051 0)
			(unlocked yes)
			(layer "F.Fab")
			(hide yes)
			(effects
				(font
					(size 1.016 1.016)
					(thickness 0.1524)
				)
			)
		)
		(property "Device Type" "C402H22"
			(at 1.1811 -4.2291 0)
			(unlocked yes)
			(layer "F.Fab")
			(hide yes)
			(effects
				(font
					(size 1.016 1.016)
					(thickness 0.1524)
				)
			)
		)
		(duplicate_pad_numbers_are_jumpers no)
		(fp_rect
			(start -0.4318 0.9525)
			(end 0.4318 -0.9525)
			(stroke
				(width 0)
				(type default)
			)
			(fill no)
			(layer "F.CrtYd")
		)
		(fp_rect
			(start -0.4318 0.9525)
			(end 0.4318 -0.9525)
			(stroke
				(width 0)
				(type default)
			)
			(fill no)
			(layer "F.Fab")
		)
		(pad "1" smd custom
			(at 0 -0.4445)
			(size 0.1524 0.1524)
			(layers "F.Cu" "F.Mask" "F.Paste")
			(net "PCIE_TX_CAP_N13")
			(options
				(clearance outline)
				(anchor circle)
			)
			(primitives
				(gr_poly
					(pts
						(arc
							(start 0.3048 -0.2032)
							(mid 0.275042 -0.275042)
							(end 0.2032 -0.3048)
						)
						(arc
							(start -0.2032 -0.3048)
							(mid -0.275042 -0.275042)
							(end -0.3048 -0.2032)
						)
						(arc
							(start -0.3048 0.2032)
							(mid -0.275042 0.275042)
							(end -0.2032 0.3048)
						)
						(arc
							(start 0.2032 0.3048)
							(mid 0.275042 0.275042)
							(end 0.3048 0.2032)
						)
					)
					(width 0)
					(fill yes)
				)
			)
		)
		(pad "2" smd custom
			(at 0 0.4445)
			(size 0.1524 0.1524)
			(layers "F.Cu" "F.Mask" "F.Paste")
			(net "PCIE_TX_N13")
			(options
				(clearance outline)
				(anchor circle)
			)
			(primitives
				(gr_poly
					(pts
						(arc
							(start 0.3048 -0.2032)
							(mid 0.275042 -0.275042)
							(end 0.2032 -0.3048)
						)
						(arc
							(start -0.2032 -0.3048)
							(mid -0.275042 -0.275042)
							(end -0.3048 -0.2032)
						)
						(arc
							(start -0.3048 0.2032)
							(mid -0.275042 0.275042)
							(end -0.2032 0.3048)
						)
						(arc
							(start 0.2032 0.3048)
							(mid 0.275042 0.275042)
							(end 0.3048 0.2032)
						)
					)
					(width 0)
					(fill yes)
				)
			)
		)
	)
	(footprint ""
		(layer "F.Cu")
		(at 20.6502 -188.1886 -90)
		(property "Reference" "R2098"
			(at 0 0 270)
			(layer "F.SilkS")
			(hide yes)
			(effects
				(font
					(size 1.27 1.27)
				)
			)
		)
		(property "Value" "10R2F-L-GP"
			(at 0.064008 -3.993896 270)
			(unlocked yes)
			(layer "F.Fab")
			(hide yes)
			(effects
				(font
					(size 1.016 1.016)
					(thickness 0.1524)
				)
			)
		)
		(property "Device Type" "R402H14"
			(at 0.064008 -5.517896 270)
			(unlocked yes)
			(layer "F.Fab")
			(hide yes)
			(effects
				(font
					(size 1.016 1.016)
					(thickness 0.1524)
				)
			)
		)
		(duplicate_pad_numbers_are_jumpers no)
		(fp_line
			(start -0.508 -0.9398)
			(end -0.508 0.9398)
			(stroke
				(width 0.1524)
				(type default)
			)
			(layer "F.SilkS")
		)
		(fp_line
			(start 0.508 -0.9398)
			(end -0.508 -0.9398)
			(stroke
				(width 0.1524)
				(type default)
			)
			(layer "F.SilkS")
		)
		(fp_rect
			(start -0.508 0.9398)
			(end 0.508 -0.9398)
			(stroke
				(width 0)
				(type default)
			)
			(fill no)
			(layer "F.CrtYd")
		)
		(fp_rect
			(start -0.508 0.9398)
			(end 0.508 -0.9398)
			(stroke
				(width 0)
				(type default)
			)
			(fill no)
			(layer "F.Fab")
		)
		(pad "1" smd custom
			(at 0 -0.4445 270)
			(size 0.1397 0.1397)
			(layers "F.Cu" "F.Mask" "F.Paste")
			(net "P12V_PCIE")
			(options
				(clearance outline)
				(anchor circle)
			)
			(primitives
				(gr_poly
					(pts
						(arc
							(start -0.1778 -0.2794)
							(mid -0.249642 -0.249642)
							(end -0.2794 -0.1778)
						)
						(arc
							(start -0.2794 0.1778)
							(mid -0.249642 0.249642)
							(end -0.1778 0.2794)
						)
						(arc
							(start 0.1778 0.2794)
							(mid 0.249642 0.249642)
							(end 0.2794 0.1778)
						)
						(arc
							(start 0.2794 -0.1778)
							(mid 0.249642 -0.249642)
							(end 0.1778 -0.2794)
						)
					)
					(width 0)
					(fill yes)
				)
			)
		)
		(pad "2" smd custom
			(at 0 0.4445 270)
			(size 0.1397 0.1397)
			(layers "F.Cu" "F.Mask" "F.Paste")
			(net "MB0_VCC")
			(options
				(clearance outline)
				(anchor circle)
			)
			(primitives
				(gr_poly
					(pts
						(arc
							(start -0.1778 -0.2794)
							(mid -0.249642 -0.249642)
							(end -0.2794 -0.1778)
						)
						(arc
							(start -0.2794 0.1778)
							(mid -0.249642 0.249642)
							(end -0.1778 0.2794)
						)
						(arc
							(start 0.1778 0.2794)
							(mid 0.249642 0.249642)
							(end 0.2794 0.1778)
						)
						(arc
							(start 0.2794 -0.1778)
							(mid 0.249642 -0.249642)
							(end 0.1778 -0.2794)
						)
					)
					(width 0)
					(fill yes)
				)
			)
		)
	)
	(footprint ""
		(layer "F.Cu")
		(at 181.61 -28.956 -90)
		(property "Reference" "C402"
			(at 0 0 270)
			(layer "F.SilkS")
			(hide yes)
			(effects
				(font
					(size 1.27 1.27)
				)
			)
		)
		(property "Value" "SCD22U10V2KX-1GP"
			(at 1.1811 -2.7051 270)
			(unlocked yes)
			(layer "F.Fab")
			(hide yes)
			(effects
				(font
					(size 1.016 1.016)
					(thickness 0.1524)
				)
			)
		)
		(property "Device Type" "C402H22"
			(at 1.1811 -4.2291 270)
			(unlocked yes)
			(layer "F.Fab")
			(hide yes)
			(effects
				(font
					(size 1.016 1.016)
					(thickness 0.1524)
				)
			)
		)
		(duplicate_pad_numbers_are_jumpers no)
		(fp_rect
			(start -0.4318 0.9525)
			(end 0.4318 -0.9525)
			(stroke
				(width 0)
				(type default)
			)
			(fill no)
			(layer "F.CrtYd")
		)
		(fp_rect
			(start -0.4318 0.9525)
			(end 0.4318 -0.9525)
			(stroke
				(width 0)
				(type default)
			)
			(fill no)
			(layer "F.Fab")
		)
		(pad "1" smd custom
			(at 0 -0.4445 270)
			(size 0.1524 0.1524)
			(layers "F.Cu" "F.Mask" "F.Paste")
			(net "PCIE_TX_CAP_N91")
			(options
				(clearance outline)
				(anchor circle)
			)
			(primitives
				(gr_poly
					(pts
						(arc
							(start 0.3048 -0.2032)
							(mid 0.275042 -0.275042)
							(end 0.2032 -0.3048)
						)
						(arc
							(start -0.2032 -0.3048)
							(mid -0.275042 -0.275042)
							(end -0.3048 -0.2032)
						)
						(arc
							(start -0.3048 0.2032)
							(mid -0.275042 0.275042)
							(end -0.2032 0.3048)
						)
						(arc
							(start 0.2032 0.3048)
							(mid 0.275042 0.275042)
							(end 0.3048 0.2032)
						)
					)
					(width 0)
					(fill yes)
				)
			)
		)
		(pad "2" smd custom
			(at 0 0.4445 270)
			(size 0.1524 0.1524)
			(layers "F.Cu" "F.Mask" "F.Paste")
			(net "PCIE_TX_N91")
			(options
				(clearance outline)
				(anchor circle)
			)
			(primitives
				(gr_poly
					(pts
						(arc
							(start 0.3048 -0.2032)
							(mid 0.275042 -0.275042)
							(end 0.2032 -0.3048)
						)
						(arc
							(start -0.2032 -0.3048)
							(mid -0.275042 -0.275042)
							(end -0.3048 -0.2032)
						)
						(arc
							(start -0.3048 0.2032)
							(mid -0.275042 0.275042)
							(end -0.2032 0.3048)
						)
						(arc
							(start 0.2032 0.3048)
							(mid 0.275042 0.275042)
							(end 0.3048 0.2032)
						)
					)
					(width 0)
					(fill yes)
				)
			)
		)
	)
	(footprint ""
		(layer "F.Cu")
		(at 107.592114 -212.420454 180)
		(property "Reference" "C147"
			(at 0 0 180)
			(layer "F.SilkS")
			(hide yes)
			(effects
				(font
					(size 1.27 1.27)
				)
			)
		)
		(property "Value" "SCD22U10V2KX-1GP"
			(at 1.1811 -2.7051 180)
			(unlocked yes)
			(layer "F.Fab")
			(hide yes)
			(effects
				(font
					(size 1.016 1.016)
					(thickness 0.1524)
				)
			)
		)
		(property "Device Type" "C402H22"
			(at 1.1811 -4.2291 180)
			(unlocked yes)
			(layer "F.Fab")
			(hide yes)
			(effects
				(font
					(size 1.016 1.016)
					(thickness 0.1524)
				)
			)
		)
		(duplicate_pad_numbers_are_jumpers no)
		(fp_rect
			(start -0.4318 0.9525)
			(end 0.4318 -0.9525)
			(stroke
				(width 0)
				(type default)
			)
			(fill no)
			(layer "F.CrtYd")
		)
		(fp_rect
			(start -0.4318 0.9525)
			(end 0.4318 -0.9525)
			(stroke
				(width 0)
				(type default)
			)
			(fill no)
			(layer "F.Fab")
		)
		(pad "1" smd custom
			(at 0 -0.4445 180)
			(size 0.1524 0.1524)
			(layers "F.Cu" "F.Mask" "F.Paste")
			(net "PCIE_TX_CAP_P60")
			(options
				(clearance outline)
				(anchor circle)
			)
			(primitives
				(gr_poly
					(pts
						(arc
							(start 0.3048 -0.2032)
							(mid 0.275042 -0.275042)
							(end 0.2032 -0.3048)
						)
						(arc
							(start -0.2032 -0.3048)
							(mid -0.275042 -0.275042)
							(end -0.3048 -0.2032)
						)
						(arc
							(start -0.3048 0.2032)
							(mid -0.275042 0.275042)
							(end -0.2032 0.3048)
						)
						(arc
							(start 0.2032 0.3048)
							(mid 0.275042 0.275042)
							(end 0.3048 0.2032)
						)
					)
					(width 0)
					(fill yes)
				)
			)
		)
		(pad "2" smd custom
			(at 0 0.4445 180)
			(size 0.1524 0.1524)
			(layers "F.Cu" "F.Mask" "F.Paste")
			(net "PCIE_TX_P60")
			(options
				(clearance outline)
				(anchor circle)
			)
			(primitives
				(gr_poly
					(pts
						(arc
							(start 0.3048 -0.2032)
							(mid 0.275042 -0.275042)
							(end 0.2032 -0.3048)
						)
						(arc
							(start -0.2032 -0.3048)
							(mid -0.275042 -0.275042)
							(end -0.3048 -0.2032)
						)
						(arc
							(start -0.3048 0.2032)
							(mid -0.275042 0.275042)
							(end -0.2032 0.3048)
						)
						(arc
							(start 0.2032 0.3048)
							(mid 0.275042 0.275042)
							(end 0.3048 0.2032)
						)
					)
					(width 0)
					(fill yes)
				)
			)
		)
	)
	(footprint ""
		(layer "F.Cu")
		(at 230.251 -80.391)
		(property "Reference" "TP171"
			(at 0 0 0)
			(layer "F.SilkS")
			(hide yes)
			(effects
				(font
					(size 1.27 1.27)
				)
			)
		)
		(property "Value" "TPAD32-GP"
			(at -0.0508 -1.6764 0)
			(unlocked yes)
			(layer "F.Fab")
			(hide yes)
			(effects
				(font
					(size 1.016 1.016)
					(thickness 0.1524)
				)
			)
		)
		(property "Device Type" "TPAD32"
			(at -0.0508 -3.2004 0)
			(unlocked yes)
			(layer "F.Fab")
			(hide yes)
			(effects
				(font
					(size 1.016 1.016)
					(thickness 0.1524)
				)
			)
		)
		(duplicate_pad_numbers_are_jumpers no)
		(fp_poly
			(pts
				(arc
					(start 0.4064 0)
					(mid -0.4064 0)
					(end 0.4064 0)
				)
			)
			(stroke
				(width 0)
				(type default)
			)
			(fill no)
			(layer "F.CrtYd")
		)
		(fp_poly
			(pts
				(arc
					(start 0.7112 0)
					(mid -0.7112 0)
					(end 0.7112 0)
				)
			)
			(stroke
				(width 0)
				(type default)
			)
			(fill no)
			(layer "F.Fab")
		)
		(pad "1" smd circle
			(at 0 0)
			(size 0.8128 0.8128)
			(layers "F.Cu" "F.Mask" "F.Paste")
			(net "TEMP_3_ALERT")
		)
	)
	(footprint ""
		(layer "F.Cu")
		(at 178.1048 -66.929 180)
		(property "Reference" "PG13"
			(at 0 0 180)
			(layer "F.SilkS")
			(hide yes)
			(effects
				(font
					(size 1.27 1.27)
				)
			)
		)
		(property "Value" "GAP-CLOSE-PWR-3-GP"
			(at 0.0254 -6.5786 180)
			(unlocked yes)
			(layer "F.Fab")
			(hide yes)
			(effects
				(font
					(size 1.016 1.016)
					(thickness 0.1524)
				)
			)
		)
		(property "Device Type" "GAP-CLOSE-PWR-3"
			(at 0.0254 -8.255 180)
			(unlocked yes)
			(layer "F.Fab")
			(hide yes)
			(effects
				(font
					(size 1.016 1.016)
					(thickness 0.1524)
				)
			)
		)
		(duplicate_pad_numbers_are_jumpers no)
		(fp_rect
			(start -0.7112 0.4572)
			(end 0.7112 -0.4572)
			(stroke
				(width 0)
				(type default)
			)
			(fill no)
			(layer "F.CrtYd")
		)
		(fp_poly
			(pts
				(xy -0.7112 -0.4572) (xy 0.7112 -0.4572) (xy 0.7112 0.4572) (xy -0.7112 0.4572)
			)
			(stroke
				(width 0)
				(type default)
			)
			(fill no)
			(layer "F.Fab")
		)
		(pad "1" smd rect
			(at -0.3048 0 180)
			(size 0.6604 0.762)
			(layers "F.Cu" "F.Mask" "F.Paste")
			(net "DUT_AVD_PCIE")
		)
		(pad "2" smd rect
			(at 0.3048 0 180)
			(size 0.6604 0.762)
			(layers "F.Cu" "F.Mask" "F.Paste")
			(net "P0V9")
		)
	)
	(footprint ""
		(layer "F.Cu")
		(at 339.884512 -172.432218)
		(property "Reference" "R7969"
			(at 0 0 0)
			(layer "F.SilkS")
			(hide yes)
			(effects
				(font
					(size 1.27 1.27)
				)
			)
		)
		(property "Value" "0R2J-2-GP"
			(at 0.064008 -3.993896 0)
			(unlocked yes)
			(layer "F.Fab")
			(hide yes)
			(effects
				(font
					(size 1.016 1.016)
					(thickness 0.1524)
				)
			)
		)
		(property "Device Type" "R402H16"
			(at 0.064008 -5.517896 0)
			(unlocked yes)
			(layer "F.Fab")
			(hide yes)
			(effects
				(font
					(size 1.016 1.016)
					(thickness 0.1524)
				)
			)
		)
		(duplicate_pad_numbers_are_jumpers no)
		(fp_line
			(start -0.508 -0.9398)
			(end -0.508 0.9398)
			(stroke
				(width 0.1524)
				(type default)
			)
			(layer "F.SilkS")
		)
		(fp_line
			(start 0.508 -0.9398)
			(end -0.508 -0.9398)
			(stroke
				(width 0.1524)
				(type default)
			)
			(layer "F.SilkS")
		)
		(fp_rect
			(start -0.508 0.9398)
			(end 0.508 -0.9398)
			(stroke
				(width 0)
				(type default)
			)
			(fill no)
			(layer "F.CrtYd")
		)
		(fp_rect
			(start -0.508 0.9398)
			(end 0.508 -0.9398)
			(stroke
				(width 0)
				(type default)
			)
			(fill no)
			(layer "F.Fab")
		)
		(pad "1" smd custom
			(at 0 -0.4445)
			(size 0.1397 0.1397)
			(layers "F.Cu" "F.Mask" "F.Paste")
			(net "SSD_PERST#9")
			(options
				(clearance outline)
				(anchor circle)
			)
			(primitives
				(gr_poly
					(pts
						(arc
							(start -0.1778 -0.2794)
							(mid -0.249642 -0.249642)
							(end -0.2794 -0.1778)
						)
						(arc
							(start -0.2794 0.1778)
							(mid -0.249642 0.249642)
							(end -0.1778 0.2794)
						)
						(arc
							(start 0.1778 0.2794)
							(mid 0.249642 0.249642)
							(end 0.2794 0.1778)
						)
						(arc
							(start 0.2794 -0.1778)
							(mid 0.249642 -0.249642)
							(end 0.1778 -0.2794)
						)
					)
					(width 0)
					(fill yes)
				)
			)
		)
		(pad "2" smd custom
			(at 0 0.4445)
			(size 0.1397 0.1397)
			(layers "F.Cu" "F.Mask" "F.Paste")
			(net "SSD_PERST#9_R")
			(options
				(clearance outline)
				(anchor circle)
			)
			(primitives
				(gr_poly
					(pts
						(arc
							(start -0.1778 -0.2794)
							(mid -0.249642 -0.249642)
							(end -0.2794 -0.1778)
						)
						(arc
							(start -0.2794 0.1778)
							(mid -0.249642 0.249642)
							(end -0.1778 0.2794)
						)
						(arc
							(start 0.1778 0.2794)
							(mid 0.249642 0.249642)
							(end 0.2794 0.1778)
						)
						(arc
							(start 0.2794 -0.1778)
							(mid 0.249642 -0.249642)
							(end 0.1778 -0.2794)
						)
					)
					(width 0)
					(fill yes)
				)
			)
		)
	)
)
